# T6G (Grand Teton) — schematic netlist excerpt (pin names and nets, part order shuffled) for the footprints in the layout excerpt that follows; sources: Cadence DE-HDL packaged netlist, KiCad conversion of 04192023_DAF0TMB3IC0_F0TG_MB_C_brd_V02_OCP.brd

C83  Q_CAP  10UF 6.3V 20% X6S  pkg C0402  page 183 : A = P3V3_9ZXL045_P1_VDDR ; B = GND
R6281  Q_RES  1K 1% EMPTY  pkg 0402LF  page 179 : A = USB_HUB2_TI_SMBUSZ_MRP_PROG_FUNC2 ; B = GND
H125  HOLE  EMPTY  pkg TH  page 230 : \1\ = NC

(kicad_pcb
	(version 20260206)
	(generator "pcbnew")
	(generator_version "10.0")
	(general
		(thickness 1.6)
		(legacy_teardrops no)
	)
	(paper "A4")
	(title_block
		(title "04192023_DAF0TMB3IC0_F0TG_MB_C_brd_V02_OCP.brd")
		(comment 1 "Grand Teton / footprints 3938-3940 of 8354")
	)
	(layers
		(0 "F.Cu" signal "TOP")
		(4 "In1.Cu" signal "GND")
		(6 "In2.Cu" signal "IN1")
		(8 "In3.Cu" signal "GND1")
		(10 "In4.Cu" signal "IN2")
		(12 "In5.Cu" signal "GND2")
		(14 "In6.Cu" signal "IN3")
		(16 "In7.Cu" signal "GND3")
		(18 "In8.Cu" signal "VCC")
		(20 "In9.Cu" signal "VCC1")
		(22 "In10.Cu" signal "GND4")
		(24 "In11.Cu" signal "IN4")
		(26 "In12.Cu" signal "GND5")
		(28 "In13.Cu" signal "IN5")
		(30 "In14.Cu" signal "GND6")
		(32 "In15.Cu" signal "IN6")
		(34 "In16.Cu" signal "GND7")
		(2 "B.Cu" signal "BOTTOM")
		(9 "F.Adhes" user "F.Adhesive")
		(11 "B.Adhes" user "B.Adhesive")
		(13 "F.Paste" user "Package Geometry/Pastemask Top")
		(15 "B.Paste" user "Package Geometry/Pastemask Bottom")
		(5 "F.SilkS" user "Ref Des/Silkscreen Top")
		(7 "B.SilkS" user "Ref Des/Silkscreen Bottom")
		(1 "F.Mask" user "Board Geometry/Soldermask Top")
		(3 "B.Mask" user "Board Geometry/Soldermask Bottom")
		(17 "Dwgs.User" user "User.Drawings")
		(19 "Cmts.User" user "User.Comments")
		(21 "Eco1.User" user "User.Eco1")
		(23 "Eco2.User" user "User.Eco2")
		(25 "Edge.Cuts" user "Board Geometry/Outline")
		(27 "Margin" user)
		(31 "F.CrtYd" user "Package Geometry/Place Bound Top")
		(29 "B.CrtYd" user "Package Geometry/Place Bound Bottom")
		(35 "F.Fab" user "Ref Des/Assembly Top")
		(33 "B.Fab" user "Ref Des/Assembly Bottom")
	)
	(footprint ""
		(layer "F.Cu")
		(at 106.934 -416.306 180)
		(property "Reference" "C83"
			(at 0 0 180)
			(layer "F.SilkS")
			(hide yes)
			(effects
				(font
					(size 1.27 1.27)
				)
			)
		)
		(property "Value" ""
			(at 0 0 180)
			(layer "F.Fab")
			(effects
				(font
					(size 1.27 1.27)
				)
			)
		)
		(duplicate_pad_numbers_are_jumpers no)
		(fp_line
			(start 0.7874 0.4064)
			(end -0.7874 0.4064)
			(stroke
				(width 0.1524)
				(type default)
			)
			(layer "F.SilkS")
		)
		(fp_line
			(start 0.7874 -0.4064)
			(end 0.7874 0.4064)
			(stroke
				(width 0.1524)
				(type default)
			)
			(layer "F.SilkS")
		)
		(fp_line
			(start -0.7874 0.4064)
			(end -0.7874 -0.4064)
			(stroke
				(width 0.1524)
				(type default)
			)
			(layer "F.SilkS")
		)
		(fp_line
			(start -0.7874 -0.4064)
			(end 0.7874 -0.4064)
			(stroke
				(width 0.1524)
				(type default)
			)
			(layer "F.SilkS")
		)
		(fp_line
			(start 0.67945 0.3048)
			(end 0.120396 0.3048)
			(stroke
				(width 0.1)
				(type default)
			)
			(layer "F.Fab")
		)
		(fp_line
			(start 0.67945 -0.3048)
			(end 0.67945 0.3048)
			(stroke
				(width 0.1)
				(type default)
			)
			(layer "F.Fab")
		)
		(fp_line
			(start 0.12065 -0.2794)
			(end 0.12065 -0.3048)
			(stroke
				(width 0.1)
				(type default)
			)
			(layer "F.Fab")
		)
		(fp_line
			(start 0.12065 -0.3048)
			(end 0.67945 -0.3048)
			(stroke
				(width 0.1)
				(type default)
			)
			(layer "F.Fab")
		)
		(fp_line
			(start 0.120396 0.3048)
			(end 0.120396 0.2794)
			(stroke
				(width 0.1)
				(type default)
			)
			(layer "F.Fab")
		)
		(fp_line
			(start 0.120396 0.2794)
			(end -0.12065 0.2794)
			(stroke
				(width 0.1)
				(type default)
			)
			(layer "F.Fab")
		)
		(fp_line
			(start -0.12065 0.3048)
			(end -0.67945 0.3048)
			(stroke
				(width 0.1)
				(type default)
			)
			(layer "F.Fab")
		)
		(fp_line
			(start -0.12065 0.2794)
			(end -0.12065 0.3048)
			(stroke
				(width 0.1)
				(type default)
			)
			(layer "F.Fab")
		)
		(fp_line
			(start -0.12065 -0.2794)
			(end 0.12065 -0.2794)
			(stroke
				(width 0.1)
				(type default)
			)
			(layer "F.Fab")
		)
		(fp_line
			(start -0.12065 -0.305054)
			(end -0.12065 -0.2794)
			(stroke
				(width 0.1)
				(type default)
			)
			(layer "F.Fab")
		)
		(fp_line
			(start -0.67945 0.3048)
			(end -0.67945 -0.305054)
			(stroke
				(width 0.1)
				(type default)
			)
			(layer "F.Fab")
		)
		(fp_line
			(start -0.67945 -0.305054)
			(end -0.12065 -0.305054)
			(stroke
				(width 0.1)
				(type default)
			)
			(layer "F.Fab")
		)
		(pad "1" smd circle
			(at -0.40005 0 180)
			(size 0 0)
			(layers "F.Cu" "F.Mask" "F.Paste")
			(net "P3V3_9ZXL045_P1_VDDR")
		)
		(pad "2" smd circle
			(at 0.40005 0 180)
			(size 0 0)
			(layers "F.Cu" "F.Mask" "F.Paste")
			(net "GND")
		)
	)
	(footprint ""
		(layer "F.Cu")
		(at 118.363238 -41.17975 90)
		(property "Reference" "R6281"
			(at 0 0 90)
			(layer "F.SilkS")
			(hide yes)
			(effects
				(font
					(size 1.27 1.27)
				)
			)
		)
		(property "Value" ""
			(at 0 0 90)
			(layer "F.Fab")
			(effects
				(font
					(size 1.27 1.27)
				)
			)
		)
		(duplicate_pad_numbers_are_jumpers no)
		(fp_line
			(start 0.7874 -0.4064)
			(end 0.7874 0.4064)
			(stroke
				(width 0.1524)
				(type default)
			)
			(layer "F.SilkS")
		)
		(fp_line
			(start -0.7874 -0.4064)
			(end 0.7874 -0.4064)
			(stroke
				(width 0.1524)
				(type default)
			)
			(layer "F.SilkS")
		)
		(fp_line
			(start 0.7874 0.4064)
			(end -0.7874 0.4064)
			(stroke
				(width 0.1524)
				(type default)
			)
			(layer "F.SilkS")
		)
		(fp_line
			(start -0.7874 0.4064)
			(end -0.7874 -0.4064)
			(stroke
				(width 0.1524)
				(type default)
			)
			(layer "F.SilkS")
		)
		(fp_line
			(start -0.12065 -0.305054)
			(end -0.12065 -0.2794)
			(stroke
				(width 0.1)
				(type default)
			)
			(layer "F.Fab")
		)
		(fp_line
			(start -0.67945 -0.305054)
			(end -0.12065 -0.305054)
			(stroke
				(width 0.1)
				(type default)
			)
			(layer "F.Fab")
		)
		(fp_line
			(start 0.67945 -0.3048)
			(end 0.67945 0.3048)
			(stroke
				(width 0.1)
				(type default)
			)
			(layer "F.Fab")
		)
		(fp_line
			(start 0.12065 -0.3048)
			(end 0.67945 -0.3048)
			(stroke
				(width 0.1)
				(type default)
			)
			(layer "F.Fab")
		)
		(fp_line
			(start 0.12065 -0.2794)
			(end 0.12065 -0.3048)
			(stroke
				(width 0.1)
				(type default)
			)
			(layer "F.Fab")
		)
		(fp_line
			(start -0.12065 -0.2794)
			(end 0.12065 -0.2794)
			(stroke
				(width 0.1)
				(type default)
			)
			(layer "F.Fab")
		)
		(fp_line
			(start 0.120396 0.2794)
			(end -0.12065 0.2794)
			(stroke
				(width 0.1)
				(type default)
			)
			(layer "F.Fab")
		)
		(fp_line
			(start -0.12065 0.2794)
			(end -0.12065 0.3048)
			(stroke
				(width 0.1)
				(type default)
			)
			(layer "F.Fab")
		)
		(fp_line
			(start 0.67945 0.3048)
			(end 0.120396 0.3048)
			(stroke
				(width 0.1)
				(type default)
			)
			(layer "F.Fab")
		)
		(fp_line
			(start 0.120396 0.3048)
			(end 0.120396 0.2794)
			(stroke
				(width 0.1)
				(type default)
			)
			(layer "F.Fab")
		)
		(fp_line
			(start -0.12065 0.3048)
			(end -0.67945 0.3048)
			(stroke
				(width 0.1)
				(type default)
			)
			(layer "F.Fab")
		)
		(fp_line
			(start -0.67945 0.3048)
			(end -0.67945 -0.305054)
			(stroke
				(width 0.1)
				(type default)
			)
			(layer "F.Fab")
		)
		(pad "1" smd circle
			(at -0.40005 0 90)
			(size 0 0)
			(layers "F.Cu" "F.Mask" "F.Paste")
			(net "USB_HUB2_TI_SMBUSZ_MRP_PROG_FUNC2")
		)
		(pad "2" smd circle
			(at 0.40005 0 90)
			(size 0 0)
			(layers "F.Cu" "F.Mask" "F.Paste")
			(net "GND")
		)
	)
	(footprint ""
		(layer "F.Cu")
		(at 277.895304 -153.766012)
		(property "Reference" "H125"
			(at 5.0038 5.03047 0)
			(unlocked yes)
			(layer "F.SilkS")
			(effects
				(font
					(size 0.7874 0.5842)
					(thickness 0.1524)
				)
				(justify left)
			)
		)
		(property "Value" ""
			(at 0 0 0)
			(layer "F.Fab")
			(effects
				(font
					(size 1.27 1.27)
				)
			)
		)
		(duplicate_pad_numbers_are_jumpers no)
		(fp_circle
			(center 0 0)
			(end 5.8166 0)
			(stroke
				(width 0.1524)
				(type default)
			)
			(fill no)
			(layer "F.SilkS")
		)
		(fp_circle
			(center 0 0)
			(end 5.8166 0)
			(stroke
				(width 0.1524)
				(type default)
			)
			(fill no)
			(layer "B.SilkS")
		)
		(fp_circle
			(center 0 0)
			(end 5.8166 0)
			(stroke
				(width 0.1)
				(type default)
			)
			(fill no)
			(layer "B.Fab")
		)
		(fp_circle
			(center 0 0)
			(end 5.8166 0)
			(stroke
				(width 0.1)
				(type default)
			)
			(fill no)
			(layer "F.Fab")
		)
		(pad "" np_thru_hole circle
			(at 0 0)
			(size 10.0076 10.0076)
			(drill 10.0076)
			(layers "*.Cu" "*.Mask")
			(clearance 0.381)
			(thermal_gap 0.381)
		)
	)
)
